(kicad_pcb
	(version 20221018)
	(generator pcbnew)
	(general
    (thickness 1.586)
  )
	(paper "A4")
	(title_block
    (date "2024-03-26")
    (rev "1.1.3")
		(comment 9 "footprints 3-7 of 146")
	)
	(layers
    (0 "F.Cu" signal)
    (1 "In1.Cu" power)
    (2 "In2.Cu" power)
    (31 "B.Cu" signal)
    (32 "B.Adhes" user "B.Adhesive")
    (33 "F.Adhes" user "F.Adhesive")
    (34 "B.Paste" user)
    (35 "F.Paste" user)
    (36 "B.SilkS" user "B.Silkscreen")
    (37 "F.SilkS" user "F.Silkscreen")
    (38 "B.Mask" user)
    (39 "F.Mask" user)
    (40 "Dwgs.User" user "User.Drawings")
    (41 "Cmts.User" user "User.Comments")
    (42 "Eco1.User" user "User.Eco1")
    (43 "Eco2.User" user "User.Eco2")
    (44 "Edge.Cuts" user)
    (45 "Margin" user)
    (46 "B.CrtYd" user "B.Courtyard")
    (47 "F.CrtYd" user "F.Courtyard")
    (48 "B.Fab" user)
    (49 "F.Fab" user)
  )
	(footprint "scalenode-cm4-baseboard-footprints:Spacer_Drill3.7mm_H3mm_9774030151R" (layer "F.Cu")
    (at 193.488 60.2)
    (property "Author" "Antmicro")
    (property "License" "Apache-2.0")
    (property "MPN" "9774030151R")
    (property "Manufacturer" "Würth Elektronik")
    (property "Sheetfile" "compute-module.kicad_sch")
    (property "Sheetname" "Compute module")
    (property "ki_description" "Spacer, SMT,  Steel, Swage Round, 5.1mmx3mm, M3 Thread, WA-SMSI Series")
    (property "ki_keywords" "SPACER")
    (attr through_hole)
    (fp_text reference "SP3" (at -0.052 4.225) (layer "F.SilkS")
        (effects (font (size 0.7 0.7) (thickness 0.15)) (justify left bottom))
    )
    (fp_text value "Spacer_Drill3.7mm_H3mm_9774030151R" (at -0.102 4.398) (layer "F.Fab")
        (effects (font (size 0.7 0.7) (thickness 0.15)) (justify left bottom))
    )
    (fp_text user "${REFERENCE}" (at -2.601 6.398) (layer "F.Fab") hide
        (effects (font (size 0.7 0.7) (thickness 0.15)) (justify left bottom))
    )
    (fp_text user "License: Apache-2.0" (at -2.601 8.8) (layer "F.Fab") hide
        (effects (font (size 0.7 0.7) (thickness 0.15)) (justify left bottom))
    )
    (fp_text user "Author: Antmicro" (at -2.601 7.599) (layer "F.Fab") hide
        (effects (font (size 0.7 0.7) (thickness 0.15)) (justify left bottom))
    )
    (fp_circle (center 0 0) (end 3.1 0)
      (stroke (width 0.12) (type solid)) (fill none) (layer "F.SilkS"))
    (fp_circle (center 0 0) (end 3.15 0)
      (stroke (width 0.05) (type solid)) (fill none) (layer "F.CrtYd"))
    (pad "" smd custom (at -1.709 -1.709) (size 0.62 0.62) (layers "F.Paste")
      (options (clearance outline) (anchor circle))
      (primitives
        (gr_arc (start -0.250195 1.279127) (mid 0.285453 0.294389) (end 1.266786 -0.24747) (width 0.2))
        (gr_arc (start -0.34334 1.279127) (mid 0.221018 0.229971) (end 1.266737 -0.340731) (width 0.2))
        (gr_arc (start -0.436309 1.279127) (mid 0.15516 0.166988) (end 1.262733 -0.432988) (width 0.2))
        (gr_arc (start -0.529126 1.279127) (mid 0.093127 0.100154) (end 1.269368 -0.527248) (width 0.2))
        (gr_arc (start -0.621807 1.279127) (mid 0.0309 0.033527) (end 1.275473 -0.621136) (width 0.2))
        (gr_arc (start -0.71437 1.279127) (mid -0.037758 -0.026651) (end 1.263665 -0.711602) (width 0.2))
        (gr_arc (start -0.806826 1.279127) (mid -0.105832 -0.087398) (end 1.253445 -0.802344) (width 0.2))
        (gr_arc (start -0.899187 1.279127) (mid -0.163611 -0.158516) (end 1.272017 -0.898016) (width 0.2))
        (gr_arc (start -0.991463 1.279127) (mid -0.228522 -0.222449) (end 1.270645 -0.990112) (width 0.2))
        (gr_arc (start -1.083663 1.279127) (mid -0.294507 -0.285313) (end 1.266278 -1.081674) (width 0.2))
        (gr_line (start 1.279127 -0.250195) (end 1.279127 -1.083663) (width 0.2))
        (gr_line (start -0.250195 1.279127) (end -1.083663 1.279127) (width 0.2))
      ))
    (pad "" smd custom (at -1.709 1.7 90) (size 0.62 0.62) (layers "F.Paste")
      (options (clearance outline) (anchor circle))
      (primitives
        (gr_arc (start -0.250195 1.279127) (mid 0.285453 0.294389) (end 1.266786 -0.24747) (width 0.2))
        (gr_arc (start -0.34334 1.279127) (mid 0.221018 0.229971) (end 1.266737 -0.340731) (width 0.2))
        (gr_arc (start -0.436309 1.279127) (mid 0.15516 0.166988) (end 1.262733 -0.432988) (width 0.2))
        (gr_arc (start -0.529126 1.279127) (mid 0.093127 0.100154) (end 1.269368 -0.527248) (width 0.2))
        (gr_arc (start -0.621807 1.279127) (mid 0.0309 0.033527) (end 1.275473 -0.621136) (width 0.2))
        (gr_arc (start -0.71437 1.279127) (mid -0.037758 -0.026651) (end 1.263665 -0.711602) (width 0.2))
        (gr_arc (start -0.806826 1.279127) (mid -0.105832 -0.087398) (end 1.253445 -0.802344) (width 0.2))
        (gr_arc (start -0.899187 1.279127) (mid -0.163611 -0.158516) (end 1.272017 -0.898016) (width 0.2))
        (gr_arc (start -0.991463 1.279127) (mid -0.228522 -0.222449) (end 1.270645 -0.990112) (width 0.2))
        (gr_arc (start -1.083663 1.279127) (mid -0.294507 -0.285313) (end 1.266278 -1.081674) (width 0.2))
        (gr_line (start 1.279127 -0.250195) (end 1.279127 -1.083663) (width 0.2))
        (gr_line (start -0.250195 1.279127) (end -1.083663 1.279127) (width 0.2))
      ))
    (pad "" smd custom (at 1.7 -1.709 270) (size 0.62 0.62) (layers "F.Paste")
      (options (clearance outline) (anchor circle))
      (primitives
        (gr_arc (start -0.250195 1.279127) (mid 0.285453 0.294389) (end 1.266786 -0.24747) (width 0.2))
        (gr_arc (start -0.34334 1.279127) (mid 0.221018 0.229971) (end 1.266737 -0.340731) (width 0.2))
        (gr_arc (start -0.436309 1.279127) (mid 0.15516 0.166988) (end 1.262733 -0.432988) (width 0.2))
        (gr_arc (start -0.529126 1.279127) (mid 0.093127 0.100154) (end 1.269368 -0.527248) (width 0.2))
        (gr_arc (start -0.621807 1.279127) (mid 0.0309 0.033527) (end 1.275473 -0.621136) (width 0.2))
        (gr_arc (start -0.71437 1.279127) (mid -0.037758 -0.026651) (end 1.263665 -0.711602) (width 0.2))
        (gr_arc (start -0.806826 1.279127) (mid -0.105832 -0.087398) (end 1.253445 -0.802344) (width 0.2))
        (gr_arc (start -0.899187 1.279127) (mid -0.163611 -0.158516) (end 1.272017 -0.898016) (width 0.2))
        (gr_arc (start -0.991463 1.279127) (mid -0.228522 -0.222449) (end 1.270645 -0.990112) (width 0.2))
        (gr_arc (start -1.083663 1.279127) (mid -0.294507 -0.285313) (end 1.266278 -1.081674) (width 0.2))
        (gr_line (start 1.279127 -0.250195) (end 1.279127 -1.083663) (width 0.2))
        (gr_line (start -0.250195 1.279127) (end -1.083663 1.279127) (width 0.2))
      ))
    (pad "" smd custom (at 1.7 1.7 180) (size 0.62 0.62) (layers "F.Paste")
      (options (clearance outline) (anchor circle))
      (primitives
        (gr_arc (start -0.250195 1.279127) (mid 0.285453 0.294389) (end 1.266786 -0.24747) (width 0.2))
        (gr_arc (start -0.34334 1.279127) (mid 0.221018 0.229971) (end 1.266737 -0.340731) (width 0.2))
        (gr_arc (start -0.436309 1.279127) (mid 0.15516 0.166988) (end 1.262733 -0.432988) (width 0.2))
        (gr_arc (start -0.529126 1.279127) (mid 0.093127 0.100154) (end 1.269368 -0.527248) (width 0.2))
        (gr_arc (start -0.621807 1.279127) (mid 0.0309 0.033527) (end 1.275473 -0.621136) (width 0.2))
        (gr_arc (start -0.71437 1.279127) (mid -0.037758 -0.026651) (end 1.263665 -0.711602) (width 0.2))
        (gr_arc (start -0.806826 1.279127) (mid -0.105832 -0.087398) (end 1.253445 -0.802344) (width 0.2))
        (gr_arc (start -0.899187 1.279127) (mid -0.163611 -0.158516) (end 1.272017 -0.898016) (width 0.2))
        (gr_arc (start -0.991463 1.279127) (mid -0.228522 -0.222449) (end 1.270645 -0.990112) (width 0.2))
        (gr_arc (start -1.083663 1.279127) (mid -0.294507 -0.285313) (end 1.266278 -1.081674) (width 0.2))
        (gr_line (start 1.279127 -0.250195) (end 1.279127 -1.083663) (width 0.2))
        (gr_line (start -0.250195 1.279127) (end -1.083663 1.279127) (width 0.2))
      ))
    (pad "1" thru_hole circle (at 0 0) (size 6 6) (drill 3.7) (layers "*.Cu" "*.Mask")
      (net 218 "unconnected-(SP3-Pad1)") (pintype "passive+no_connect") (solder_paste_margin -1.2))
  )
	(footprint "scalenode-cm4-baseboard-footprints:Spacer_Drill3.7mm_H3mm_9774030151R" (layer "F.Cu")
    (at 145.488 60.2)
    (property "Author" "Antmicro")
    (property "License" "Apache-2.0")
    (property "MPN" "9774030151R")
    (property "Manufacturer" "Würth Elektronik")
    (property "Sheetfile" "compute-module.kicad_sch")
    (property "Sheetname" "Compute module")
    (property "ki_description" "Spacer, SMT,  Steel, Swage Round, 5.1mmx3mm, M3 Thread, WA-SMSI Series")
    (property "ki_keywords" "SPACER")
    (attr through_hole)
    (fp_text reference "SP2" (at -0.713 4.225) (layer "F.SilkS")
        (effects (font (size 0.7 0.7) (thickness 0.15)) (justify left bottom))
    )
    (fp_text value "Spacer_Drill3.7mm_H3mm_9774030151R" (at -0.102 4.398) (layer "F.Fab")
        (effects (font (size 0.7 0.7) (thickness 0.15)) (justify left bottom))
    )
    (fp_text user "${REFERENCE}" (at -2.601 6.398) (layer "F.Fab") hide
        (effects (font (size 0.7 0.7) (thickness 0.15)) (justify left bottom))
    )
    (fp_text user "Author: Antmicro" (at -2.601 7.599) (layer "F.Fab") hide
        (effects (font (size 0.7 0.7) (thickness 0.15)) (justify left bottom))
    )
    (fp_text user "License: Apache-2.0" (at -2.601 8.8) (layer "F.Fab") hide
        (effects (font (size 0.7 0.7) (thickness 0.15)) (justify left bottom))
    )
    (fp_circle (center 0 0) (end 3.1 0)
      (stroke (width 0.12) (type solid)) (fill none) (layer "F.SilkS"))
    (fp_circle (center 0 0) (end 3.15 0)
      (stroke (width 0.05) (type solid)) (fill none) (layer "F.CrtYd"))
    (pad "" smd custom (at -1.709 -1.709) (size 0.62 0.62) (layers "F.Paste")
      (options (clearance outline) (anchor circle))
      (primitives
        (gr_arc (start -0.250195 1.279127) (mid 0.285453 0.294389) (end 1.266786 -0.24747) (width 0.2))
        (gr_arc (start -0.34334 1.279127) (mid 0.221018 0.229971) (end 1.266737 -0.340731) (width 0.2))
        (gr_arc (start -0.436309 1.279127) (mid 0.15516 0.166988) (end 1.262733 -0.432988) (width 0.2))
        (gr_arc (start -0.529126 1.279127) (mid 0.093127 0.100154) (end 1.269368 -0.527248) (width 0.2))
        (gr_arc (start -0.621807 1.279127) (mid 0.0309 0.033527) (end 1.275473 -0.621136) (width 0.2))
        (gr_arc (start -0.71437 1.279127) (mid -0.037758 -0.026651) (end 1.263665 -0.711602) (width 0.2))
        (gr_arc (start -0.806826 1.279127) (mid -0.105832 -0.087398) (end 1.253445 -0.802344) (width 0.2))
        (gr_arc (start -0.899187 1.279127) (mid -0.163611 -0.158516) (end 1.272017 -0.898016) (width 0.2))
        (gr_arc (start -0.991463 1.279127) (mid -0.228522 -0.222449) (end 1.270645 -0.990112) (width 0.2))
        (gr_arc (start -1.083663 1.279127) (mid -0.294507 -0.285313) (end 1.266278 -1.081674) (width 0.2))
        (gr_line (start 1.279127 -0.250195) (end 1.279127 -1.083663) (width 0.2))
        (gr_line (start -0.250195 1.279127) (end -1.083663 1.279127) (width 0.2))
      ))
    (pad "" smd custom (at -1.709 1.7 90) (size 0.62 0.62) (layers "F.Paste")
      (options (clearance outline) (anchor circle))
      (primitives
        (gr_arc (start -0.250195 1.279127) (mid 0.285453 0.294389) (end 1.266786 -0.24747) (width 0.2))
        (gr_arc (start -0.34334 1.279127) (mid 0.221018 0.229971) (end 1.266737 -0.340731) (width 0.2))
        (gr_arc (start -0.436309 1.279127) (mid 0.15516 0.166988) (end 1.262733 -0.432988) (width 0.2))
        (gr_arc (start -0.529126 1.279127) (mid 0.093127 0.100154) (end 1.269368 -0.527248) (width 0.2))
        (gr_arc (start -0.621807 1.279127) (mid 0.0309 0.033527) (end 1.275473 -0.621136) (width 0.2))
        (gr_arc (start -0.71437 1.279127) (mid -0.037758 -0.026651) (end 1.263665 -0.711602) (width 0.2))
        (gr_arc (start -0.806826 1.279127) (mid -0.105832 -0.087398) (end 1.253445 -0.802344) (width 0.2))
        (gr_arc (start -0.899187 1.279127) (mid -0.163611 -0.158516) (end 1.272017 -0.898016) (width 0.2))
        (gr_arc (start -0.991463 1.279127) (mid -0.228522 -0.222449) (end 1.270645 -0.990112) (width 0.2))
        (gr_arc (start -1.083663 1.279127) (mid -0.294507 -0.285313) (end 1.266278 -1.081674) (width 0.2))
        (gr_line (start 1.279127 -0.250195) (end 1.279127 -1.083663) (width 0.2))
        (gr_line (start -0.250195 1.279127) (end -1.083663 1.279127) (width 0.2))
      ))
    (pad "" smd custom (at 1.7 -1.709 270) (size 0.62 0.62) (layers "F.Paste")
      (options (clearance outline) (anchor circle))
      (primitives
        (gr_arc (start -0.250195 1.279127) (mid 0.285453 0.294389) (end 1.266786 -0.24747) (width 0.2))
        (gr_arc (start -0.34334 1.279127) (mid 0.221018 0.229971) (end 1.266737 -0.340731) (width 0.2))
        (gr_arc (start -0.436309 1.279127) (mid 0.15516 0.166988) (end 1.262733 -0.432988) (width 0.2))
        (gr_arc (start -0.529126 1.279127) (mid 0.093127 0.100154) (end 1.269368 -0.527248) (width 0.2))
        (gr_arc (start -0.621807 1.279127) (mid 0.0309 0.033527) (end 1.275473 -0.621136) (width 0.2))
        (gr_arc (start -0.71437 1.279127) (mid -0.037758 -0.026651) (end 1.263665 -0.711602) (width 0.2))
        (gr_arc (start -0.806826 1.279127) (mid -0.105832 -0.087398) (end 1.253445 -0.802344) (width 0.2))
        (gr_arc (start -0.899187 1.279127) (mid -0.163611 -0.158516) (end 1.272017 -0.898016) (width 0.2))
        (gr_arc (start -0.991463 1.279127) (mid -0.228522 -0.222449) (end 1.270645 -0.990112) (width 0.2))
        (gr_arc (start -1.083663 1.279127) (mid -0.294507 -0.285313) (end 1.266278 -1.081674) (width 0.2))
        (gr_line (start 1.279127 -0.250195) (end 1.279127 -1.083663) (width 0.2))
        (gr_line (start -0.250195 1.279127) (end -1.083663 1.279127) (width 0.2))
      ))
    (pad "" smd custom (at 1.7 1.7 180) (size 0.62 0.62) (layers "F.Paste")
      (options (clearance outline) (anchor circle))
      (primitives
        (gr_arc (start -0.250195 1.279127) (mid 0.285453 0.294389) (end 1.266786 -0.24747) (width 0.2))
        (gr_arc (start -0.34334 1.279127) (mid 0.221018 0.229971) (end 1.266737 -0.340731) (width 0.2))
        (gr_arc (start -0.436309 1.279127) (mid 0.15516 0.166988) (end 1.262733 -0.432988) (width 0.2))
        (gr_arc (start -0.529126 1.279127) (mid 0.093127 0.100154) (end 1.269368 -0.527248) (width 0.2))
        (gr_arc (start -0.621807 1.279127) (mid 0.0309 0.033527) (end 1.275473 -0.621136) (width 0.2))
        (gr_arc (start -0.71437 1.279127) (mid -0.037758 -0.026651) (end 1.263665 -0.711602) (width 0.2))
        (gr_arc (start -0.806826 1.279127) (mid -0.105832 -0.087398) (end 1.253445 -0.802344) (width 0.2))
        (gr_arc (start -0.899187 1.279127) (mid -0.163611 -0.158516) (end 1.272017 -0.898016) (width 0.2))
        (gr_arc (start -0.991463 1.279127) (mid -0.228522 -0.222449) (end 1.270645 -0.990112) (width 0.2))
        (gr_arc (start -1.083663 1.279127) (mid -0.294507 -0.285313) (end 1.266278 -1.081674) (width 0.2))
        (gr_line (start 1.279127 -0.250195) (end 1.279127 -1.083663) (width 0.2))
        (gr_line (start -0.250195 1.279127) (end -1.083663 1.279127) (width 0.2))
      ))
    (pad "1" thru_hole circle (at 0 0) (size 6 6) (drill 3.7) (layers "*.Cu" "*.Mask")
      (net 217 "unconnected-(SP2-Pad1)") (pintype "passive+no_connect") (solder_paste_margin -1.2))
  )
	(footprint "scalenode-cm4-baseboard-footprints:R_0402_1005Metric" (layer "F.Cu")
    (at 159.99 74.67 -90)
    (descr "Resistor SMD 0402")
    (tags "resistor SMD 0402")
    (property "Author" "Antmicro")
    (property "License" "Apache-2.0")
    (property "MPN" "CR0402-FX-2201GLF")
    (property "Manufacturer" "Bourns")
    (property "Sheetfile" "interfaces.kicad_sch")
    (property "Sheetname" "Interfaces")
    (property "Tolerance" "1%")
    (property "Val" "2k2")
    (property "ki_description" "2k2 resistor in 0402 package with 1% tolerance")
    (attr smd)
    (fp_text reference "R15" (at 1.1 -1.41 90) (layer "F.SilkS")
        (effects (font (size 0.7 0.7) (thickness 0.15)) (justify left bottom))
    )
    (fp_text value "R_2k2_0402" (at 0 1.4 -90) (layer "F.Fab")
        (effects (font (size 0.7 0.7) (thickness 0.15)) (justify left bottom))
    )
    (fp_text user "Author: Antmicro" (at -0.95 4.169 -90) (layer "F.Fab") hide
        (effects (font (size 0.7 0.7) (thickness 0.15)) (justify left bottom))
    )
    (fp_text user "License: Apache-2.0" (at -0.95 5.169 -90) (layer "F.Fab") hide
        (effects (font (size 0.7 0.7) (thickness 0.15)) (justify left bottom))
    )
    (fp_text user "${REFERENCE}" (at -0.95 3.168 -90) (layer "F.Fab") hide
        (effects (font (size 0.7 0.7) (thickness 0.15)) (justify left bottom))
    )
    (fp_rect (start -0.95 -0.48) (end 0.95 0.48)
      (stroke (width 0.05) (type solid)) (fill none) (layer "F.CrtYd"))
    (fp_rect (start -0.5 -0.25) (end 0.5 0.25)
      (stroke (width 0.15) (type solid)) (fill none) (layer "F.Fab"))
    (pad "1" smd roundrect (at -0.485 0 270) (size 0.59 0.64) (layers "F.Cu" "F.Paste" "F.Mask") (roundrect_rratio 0.25)
      (net 11 "GND") (pintype "passive"))
    (pad "2" smd roundrect (at 0.485 0 270) (size 0.59 0.64) (layers "F.Cu" "F.Paste" "F.Mask") (roundrect_rratio 0.25)
      (net 95 "USBOTG_ID") (pintype "passive"))
  )
	(footprint "scalenode-cm4-baseboard-footprints:C_0402_1005Metric" (layer "F.Cu")
    (at 174.7652 83.7128)
    (descr "Capacitor SMD 0402")
    (tags "capacitor SMD 0402")
    (property "Author" "Antmicro")
    (property "Dielectric" "")
    (property "License" "Apache-2.0")
    (property "MPN" "C1005X6S1A105K050BC")
    (property "Manufacturer" "TDK")
    (property "Sheetfile" "interfaces.kicad_sch")
    (property "Sheetname" "Interfaces")
    (property "Val" "1u")
    (property "Voltage" "")
    (property "ki_description" " ")
    (attr smd)
    (fp_text reference "C14" (at 0.8848 0.3122) (layer "F.SilkS")
        (effects (font (size 0.7 0.7) (thickness 0.15)) (justify left bottom))
    )
    (fp_text value "C_1u_0402" (at 0 1.4) (layer "F.Fab")
        (effects (font (size 0.7 0.7) (thickness 0.15)) (justify left bottom))
    )
    (fp_text user "Author: Antmicro" (at -0.932 4.17) (layer "F.Fab") hide
        (effects (font (size 0.7 0.7) (thickness 0.15)) (justify left bottom))
    )
    (fp_text user "${REFERENCE}" (at -0.932 3.168) (layer "F.Fab") hide
        (effects (font (size 0.7 0.7) (thickness 0.15)) (justify left bottom))
    )
    (fp_text user "License: Apache-2.0" (at -0.932 5.17) (layer "F.Fab") hide
        (effects (font (size 0.7 0.7) (thickness 0.15)) (justify left bottom))
    )
    (fp_rect (start -0.94 -0.47) (end 0.94 0.47)
      (stroke (width 0.05) (type solid)) (fill none) (layer "F.CrtYd"))
    (fp_rect (start -0.499 -0.249) (end 0.499 0.249)
      (stroke (width 0.15) (type solid)) (fill none) (layer "F.Fab"))
    (pad "1" smd roundrect (at -0.484 0) (size 0.59 0.64) (layers "F.Cu" "F.Paste" "F.Mask") (roundrect_rratio 0.25)
      (net 232 "3V3_RPi") (pintype "passive"))
    (pad "2" smd roundrect (at 0.484 0) (size 0.59 0.64) (layers "F.Cu" "F.Paste" "F.Mask") (roundrect_rratio 0.25)
      (net 11 "GND") (pintype "passive"))
  )
	(footprint "scalenode-cm4-baseboard-footprints:C_0402_1005Metric" (layer "F.Cu")
    (at 174.7652 82.6968)
    (descr "Capacitor SMD 0402")
    (tags "capacitor SMD 0402")
    (property "Author" "Antmicro")
    (property "Dielectric" "X5R")
    (property "License" "Apache-2.0")
    (property "MPN" "GRM155R61H104KE14D")
    (property "Manufacturer" "Murata")
    (property "Sheetfile" "interfaces.kicad_sch")
    (property "Sheetname" "Interfaces")
    (property "Val" "100n")
    (property "Voltage" "50V")
    (property "ki_description" " ")
    (attr smd)
    (fp_text reference "C13" (at 0.8848 0.3532) (layer "F.SilkS")
        (effects (font (size 0.7 0.7) (thickness 0.15)) (justify left bottom))
    )
    (fp_text value "C_100n_0402" (at 0 1.4) (layer "F.Fab")
        (effects (font (size 0.7 0.7) (thickness 0.15)) (justify left bottom))
    )
    (fp_text user "Author: Antmicro" (at -0.932 4.17) (layer "F.Fab") hide
        (effects (font (size 0.7 0.7) (thickness 0.15)) (justify left bottom))
    )
    (fp_text user "${REFERENCE}" (at -0.932 3.168) (layer "F.Fab") hide
        (effects (font (size 0.7 0.7) (thickness 0.15)) (justify left bottom))
    )
    (fp_text user "License: Apache-2.0" (at -0.932 5.17) (layer "F.Fab") hide
        (effects (font (size 0.7 0.7) (thickness 0.15)) (justify left bottom))
    )
    (fp_rect (start -0.94 -0.47) (end 0.94 0.47)
      (stroke (width 0.05) (type solid)) (fill none) (layer "F.CrtYd"))
    (fp_rect (start -0.499 -0.249) (end 0.499 0.249)
      (stroke (width 0.15) (type solid)) (fill none) (layer "F.Fab"))
    (pad "1" smd roundrect (at -0.484 0) (size 0.59 0.64) (layers "F.Cu" "F.Paste" "F.Mask") (roundrect_rratio 0.25)
      (net 232 "3V3_RPi") (pintype "passive"))
    (pad "2" smd roundrect (at 0.484 0) (size 0.59 0.64) (layers "F.Cu" "F.Paste" "F.Mask") (roundrect_rratio 0.25)
      (net 11 "GND") (pintype "passive"))
  )
)
